(kicad_pcb
	(version 20260206)
	(generator "pcbnew")
	(generator_version "10.0")
	(general
		(thickness 1.6)
		(legacy_teardrops no)
	)
	(paper "A4")
	(title_block
		(title "Bryce Canyon_SCC_16316-1_OCP.brd")
		(comment 1 "Bryce Canyon / footprints 444-451 of 1561")
	)
	(layers
		(0 "F.Cu" signal "TOP")
		(4 "In1.Cu" signal "L2GND")
		(6 "In2.Cu" signal "L3")
		(8 "In3.Cu" signal "L4VCC")
		(10 "In4.Cu" signal "L5VCC")
		(12 "In5.Cu" signal "L6")
		(14 "In6.Cu" signal "L7GND")
		(2 "B.Cu" signal "BOTTOM")
		(9 "F.Adhes" user "F.Adhesive")
		(11 "B.Adhes" user "B.Adhesive")
		(13 "F.Paste" user "Package Geometry/Pastemask Top")
		(15 "B.Paste" user "Package Geometry/Pastemask Bottom")
		(5 "F.SilkS" user "Ref Des/Silkscreen Top")
		(7 "B.SilkS" user "Ref Des/Silkscreen Bottom")
		(1 "F.Mask" user "Board Geometry/Soldermask Top")
		(3 "B.Mask" user "Board Geometry/Soldermask Bottom")
		(17 "Dwgs.User" user "User.Drawings")
		(19 "Cmts.User" user "User.Comments")
		(21 "Eco1.User" user "User.Eco1")
		(23 "Eco2.User" user "User.Eco2")
		(25 "Edge.Cuts" user "Board Geometry/Outline")
		(27 "Margin" user)
		(31 "F.CrtYd" user "Package Geometry/Place Bound Top")
		(29 "B.CrtYd" user "Package Geometry/Place Bound Bottom")
		(35 "F.Fab" user "Ref Des/Assembly Top")
		(33 "B.Fab" user "Ref Des/Assembly Bottom")
	)
	(footprint ""
		(layer "F.Cu")
		(at 109.782356 -90.518742 90)
		(property "Reference" "R580"
			(at 0 0 90)
			(layer "F.SilkS")
			(hide yes)
			(effects
				(font
					(size 1.27 1.27)
				)
			)
		)
		(property "Value" "10KR2F-2-GP"
			(at 0.064008 -3.993896 90)
			(unlocked yes)
			(layer "F.Fab")
			(hide yes)
			(effects
				(font
					(size 1.016 1.016)
					(thickness 0.1524)
				)
			)
		)
		(property "Device Type" "R402H16"
			(at 0.064008 -5.517896 90)
			(unlocked yes)
			(layer "F.Fab")
			(hide yes)
			(effects
				(font
					(size 1.016 1.016)
					(thickness 0.1524)
				)
			)
		)
		(duplicate_pad_numbers_are_jumpers no)
		(fp_line
			(start 0.508 -0.9398)
			(end -0.508 -0.9398)
			(stroke
				(width 0.1524)
				(type default)
			)
			(layer "F.SilkS")
		)
		(fp_line
			(start -0.508 -0.9398)
			(end -0.508 0.9398)
			(stroke
				(width 0.1524)
				(type default)
			)
			(layer "F.SilkS")
		)
		(fp_rect
			(start -0.508 0.9398)
			(end 0.508 -0.9398)
			(stroke
				(width 0)
				(type default)
			)
			(fill no)
			(layer "F.CrtYd")
		)
		(fp_rect
			(start -0.508 0.9398)
			(end 0.508 -0.9398)
			(stroke
				(width 0)
				(type default)
			)
			(fill no)
			(layer "F.Fab")
		)
		(pad "1" smd custom
			(at 0 -0.4445 90)
			(size 0.1397 0.1397)
			(layers "F.Cu" "F.Mask" "F.Paste")
			(net "SCC_LOC_HEARTBEAT_LS")
			(options
				(clearance outline)
				(anchor circle)
			)
			(primitives
				(gr_poly
					(pts
						(arc
							(start -0.1778 -0.2794)
							(mid -0.249642 -0.249642)
							(end -0.2794 -0.1778)
						)
						(arc
							(start -0.2794 0.1778)
							(mid -0.249642 0.249642)
							(end -0.1778 0.2794)
						)
						(arc
							(start 0.1778 0.2794)
							(mid 0.249642 0.249642)
							(end 0.2794 0.1778)
						)
						(arc
							(start 0.2794 -0.1778)
							(mid 0.249642 -0.249642)
							(end 0.1778 -0.2794)
						)
					)
					(width 0)
					(fill yes)
				)
			)
		)
		(pad "2" smd custom
			(at 0 0.4445 90)
			(size 0.1397 0.1397)
			(layers "F.Cu" "F.Mask" "F.Paste")
			(net "P1V8_E")
			(options
				(clearance outline)
				(anchor circle)
			)
			(primitives
				(gr_poly
					(pts
						(arc
							(start -0.1778 -0.2794)
							(mid -0.249642 -0.249642)
							(end -0.2794 -0.1778)
						)
						(arc
							(start -0.2794 0.1778)
							(mid -0.249642 0.249642)
							(end -0.1778 0.2794)
						)
						(arc
							(start 0.1778 0.2794)
							(mid 0.249642 0.249642)
							(end 0.2794 0.1778)
						)
						(arc
							(start 0.2794 -0.1778)
							(mid 0.249642 -0.249642)
							(end 0.1778 -0.2794)
						)
					)
					(width 0)
					(fill yes)
				)
			)
		)
	)
	(footprint ""
		(layer "F.Cu")
		(at 119.912638 -91.094052 -90)
		(property "Reference" "R44"
			(at 0 0 270)
			(layer "F.SilkS")
			(hide yes)
			(effects
				(font
					(size 1.27 1.27)
				)
			)
		)
		(property "Value" "4K7R2F-GP"
			(at 0.064008 -3.993896 270)
			(unlocked yes)
			(layer "F.Fab")
			(hide yes)
			(effects
				(font
					(size 1.016 1.016)
					(thickness 0.1524)
				)
			)
		)
		(property "Device Type" "R402H16"
			(at 0.064008 -5.517896 270)
			(unlocked yes)
			(layer "F.Fab")
			(hide yes)
			(effects
				(font
					(size 1.016 1.016)
					(thickness 0.1524)
				)
			)
		)
		(duplicate_pad_numbers_are_jumpers no)
		(fp_line
			(start -0.508 -0.9398)
			(end -0.508 0.9398)
			(stroke
				(width 0.1524)
				(type default)
			)
			(layer "F.SilkS")
		)
		(fp_line
			(start 0.508 -0.9398)
			(end -0.508 -0.9398)
			(stroke
				(width 0.1524)
				(type default)
			)
			(layer "F.SilkS")
		)
		(fp_rect
			(start -0.508 0.9398)
			(end 0.508 -0.9398)
			(stroke
				(width 0)
				(type default)
			)
			(fill no)
			(layer "F.CrtYd")
		)
		(fp_rect
			(start -0.508 0.9398)
			(end 0.508 -0.9398)
			(stroke
				(width 0)
				(type default)
			)
			(fill no)
			(layer "F.Fab")
		)
		(pad "1" smd custom
			(at 0 -0.4445 270)
			(size 0.1397 0.1397)
			(layers "F.Cu" "F.Mask" "F.Paste")
			(net "EXP_GPIO13")
			(options
				(clearance outline)
				(anchor circle)
			)
			(primitives
				(gr_poly
					(pts
						(arc
							(start -0.1778 -0.2794)
							(mid -0.249642 -0.249642)
							(end -0.2794 -0.1778)
						)
						(arc
							(start -0.2794 0.1778)
							(mid -0.249642 0.249642)
							(end -0.1778 0.2794)
						)
						(arc
							(start 0.1778 0.2794)
							(mid 0.249642 0.249642)
							(end 0.2794 0.1778)
						)
						(arc
							(start 0.2794 -0.1778)
							(mid 0.249642 -0.249642)
							(end 0.1778 -0.2794)
						)
					)
					(width 0)
					(fill yes)
				)
			)
		)
		(pad "2" smd custom
			(at 0 0.4445 270)
			(size 0.1397 0.1397)
			(layers "F.Cu" "F.Mask" "F.Paste")
			(net "GND")
			(options
				(clearance outline)
				(anchor circle)
			)
			(primitives
				(gr_poly
					(pts
						(arc
							(start -0.1778 -0.2794)
							(mid -0.249642 -0.249642)
							(end -0.2794 -0.1778)
						)
						(arc
							(start -0.2794 0.1778)
							(mid -0.249642 0.249642)
							(end -0.1778 0.2794)
						)
						(arc
							(start 0.1778 0.2794)
							(mid 0.249642 0.249642)
							(end 0.2794 0.1778)
						)
						(arc
							(start 0.2794 -0.1778)
							(mid 0.249642 -0.249642)
							(end 0.1778 -0.2794)
						)
					)
					(width 0)
					(fill yes)
				)
			)
		)
	)
	(footprint ""
		(layer "F.Cu")
		(at 64.897 -106.045 180)
		(property "Reference" "R517"
			(at 0 0 180)
			(layer "F.SilkS")
			(hide yes)
			(effects
				(font
					(size 1.27 1.27)
				)
			)
		)
		(property "Value" "0R2J-2-GP"
			(at 0.064008 -3.993896 180)
			(unlocked yes)
			(layer "F.Fab")
			(hide yes)
			(effects
				(font
					(size 1.016 1.016)
					(thickness 0.1524)
				)
			)
		)
		(property "Device Type" "R402H16"
			(at 0.064008 -5.517896 180)
			(unlocked yes)
			(layer "F.Fab")
			(hide yes)
			(effects
				(font
					(size 1.016 1.016)
					(thickness 0.1524)
				)
			)
		)
		(duplicate_pad_numbers_are_jumpers no)
		(fp_line
			(start 0.508 -0.9398)
			(end -0.508 -0.9398)
			(stroke
				(width 0.1524)
				(type default)
			)
			(layer "F.SilkS")
		)
		(fp_line
			(start -0.508 -0.9398)
			(end -0.508 0.9398)
			(stroke
				(width 0.1524)
				(type default)
			)
			(layer "F.SilkS")
		)
		(fp_rect
			(start -0.508 0.9398)
			(end 0.508 -0.9398)
			(stroke
				(width 0)
				(type default)
			)
			(fill no)
			(layer "F.CrtYd")
		)
		(fp_rect
			(start -0.508 0.9398)
			(end 0.508 -0.9398)
			(stroke
				(width 0)
				(type default)
			)
			(fill no)
			(layer "F.Fab")
		)
		(pad "1" smd custom
			(at 0 -0.4445 180)
			(size 0.1397 0.1397)
			(layers "F.Cu" "F.Mask" "F.Paste")
			(net "P3V3_ROVP")
			(options
				(clearance outline)
				(anchor circle)
			)
			(primitives
				(gr_poly
					(pts
						(arc
							(start -0.1778 -0.2794)
							(mid -0.249642 -0.249642)
							(end -0.2794 -0.1778)
						)
						(arc
							(start -0.2794 0.1778)
							(mid -0.249642 0.249642)
							(end -0.1778 0.2794)
						)
						(arc
							(start 0.1778 0.2794)
							(mid 0.249642 0.249642)
							(end 0.2794 0.1778)
						)
						(arc
							(start 0.2794 -0.1778)
							(mid 0.249642 -0.249642)
							(end 0.1778 -0.2794)
						)
					)
					(width 0)
					(fill yes)
				)
			)
		)
		(pad "2" smd custom
			(at 0 0.4445 180)
			(size 0.1397 0.1397)
			(layers "F.Cu" "F.Mask" "F.Paste")
			(net "AGND_P3V3")
			(options
				(clearance outline)
				(anchor circle)
			)
			(primitives
				(gr_poly
					(pts
						(arc
							(start -0.1778 -0.2794)
							(mid -0.249642 -0.249642)
							(end -0.2794 -0.1778)
						)
						(arc
							(start -0.2794 0.1778)
							(mid -0.249642 0.249642)
							(end -0.1778 0.2794)
						)
						(arc
							(start 0.1778 0.2794)
							(mid 0.249642 0.249642)
							(end 0.2794 0.1778)
						)
						(arc
							(start 0.2794 -0.1778)
							(mid 0.249642 -0.249642)
							(end 0.1778 -0.2794)
						)
					)
					(width 0)
					(fill yes)
				)
			)
		)
	)
	(footprint ""
		(layer "F.Cu")
		(at 105.877614 -86.889336)
		(property "Reference" "R87"
			(at 0 0 0)
			(layer "F.SilkS")
			(hide yes)
			(effects
				(font
					(size 1.27 1.27)
				)
			)
		)
		(property "Value" "4K75R2F-1-GP"
			(at 0.064008 -3.993896 0)
			(unlocked yes)
			(layer "F.Fab")
			(hide yes)
			(effects
				(font
					(size 1.016 1.016)
					(thickness 0.1524)
				)
			)
		)
		(property "Device Type" "R402H16"
			(at 0.064008 -5.517896 0)
			(unlocked yes)
			(layer "F.Fab")
			(hide yes)
			(effects
				(font
					(size 1.016 1.016)
					(thickness 0.1524)
				)
			)
		)
		(duplicate_pad_numbers_are_jumpers no)
		(fp_line
			(start -0.508 -0.9398)
			(end -0.508 0.9398)
			(stroke
				(width 0.1524)
				(type default)
			)
			(layer "F.SilkS")
		)
		(fp_line
			(start 0.508 -0.9398)
			(end -0.508 -0.9398)
			(stroke
				(width 0.1524)
				(type default)
			)
			(layer "F.SilkS")
		)
		(fp_rect
			(start -0.508 0.9398)
			(end 0.508 -0.9398)
			(stroke
				(width 0)
				(type default)
			)
			(fill no)
			(layer "F.CrtYd")
		)
		(fp_rect
			(start -0.508 0.9398)
			(end 0.508 -0.9398)
			(stroke
				(width 0)
				(type default)
			)
			(fill no)
			(layer "F.Fab")
		)
		(pad "1" smd custom
			(at 0 -0.4445)
			(size 0.1397 0.1397)
			(layers "F.Cu" "F.Mask" "F.Paste")
			(net "P1V8_E")
			(options
				(clearance outline)
				(anchor circle)
			)
			(primitives
				(gr_poly
					(pts
						(arc
							(start -0.1778 -0.2794)
							(mid -0.249642 -0.249642)
							(end -0.2794 -0.1778)
						)
						(arc
							(start -0.2794 0.1778)
							(mid -0.249642 0.249642)
							(end -0.1778 0.2794)
						)
						(arc
							(start 0.1778 0.2794)
							(mid 0.249642 0.249642)
							(end 0.2794 0.1778)
						)
						(arc
							(start 0.2794 -0.1778)
							(mid 0.249642 -0.249642)
							(end 0.1778 -0.2794)
						)
					)
					(width 0)
					(fill yes)
				)
			)
		)
		(pad "2" smd custom
			(at 0 0.4445)
			(size 0.1397 0.1397)
			(layers "F.Cu" "F.Mask" "F.Paste")
			(net "SXP_ACTIVE_2")
			(options
				(clearance outline)
				(anchor circle)
			)
			(primitives
				(gr_poly
					(pts
						(arc
							(start -0.1778 -0.2794)
							(mid -0.249642 -0.249642)
							(end -0.2794 -0.1778)
						)
						(arc
							(start -0.2794 0.1778)
							(mid -0.249642 0.249642)
							(end -0.1778 0.2794)
						)
						(arc
							(start 0.1778 0.2794)
							(mid 0.249642 0.249642)
							(end 0.2794 0.1778)
						)
						(arc
							(start 0.2794 -0.1778)
							(mid 0.249642 -0.249642)
							(end 0.1778 -0.2794)
						)
					)
					(width 0)
					(fill yes)
				)
			)
		)
	)
	(footprint ""
		(layer "F.Cu")
		(at 117.939058 -86.995254 180)
		(property "Reference" "R142"
			(at 0 0 180)
			(layer "F.SilkS")
			(hide yes)
			(effects
				(font
					(size 1.27 1.27)
				)
			)
		)
		(property "Value" "4K7R2F-GP"
			(at 0.064008 -3.993896 180)
			(unlocked yes)
			(layer "F.Fab")
			(hide yes)
			(effects
				(font
					(size 1.016 1.016)
					(thickness 0.1524)
				)
			)
		)
		(property "Device Type" "R402H16"
			(at 0.064008 -5.517896 180)
			(unlocked yes)
			(layer "F.Fab")
			(hide yes)
			(effects
				(font
					(size 1.016 1.016)
					(thickness 0.1524)
				)
			)
		)
		(duplicate_pad_numbers_are_jumpers no)
		(fp_line
			(start 0.508 -0.9398)
			(end -0.508 -0.9398)
			(stroke
				(width 0.1524)
				(type default)
			)
			(layer "F.SilkS")
		)
		(fp_line
			(start -0.508 -0.9398)
			(end -0.508 0.9398)
			(stroke
				(width 0.1524)
				(type default)
			)
			(layer "F.SilkS")
		)
		(fp_rect
			(start -0.508 0.9398)
			(end 0.508 -0.9398)
			(stroke
				(width 0)
				(type default)
			)
			(fill no)
			(layer "F.CrtYd")
		)
		(fp_rect
			(start -0.508 0.9398)
			(end 0.508 -0.9398)
			(stroke
				(width 0)
				(type default)
			)
			(fill no)
			(layer "F.Fab")
		)
		(pad "1" smd custom
			(at 0 -0.4445 180)
			(size 0.1397 0.1397)
			(layers "F.Cu" "F.Mask" "F.Paste")
			(net "EXP_XM_ADDR_16")
			(options
				(clearance outline)
				(anchor circle)
			)
			(primitives
				(gr_poly
					(pts
						(arc
							(start -0.1778 -0.2794)
							(mid -0.249642 -0.249642)
							(end -0.2794 -0.1778)
						)
						(arc
							(start -0.2794 0.1778)
							(mid -0.249642 0.249642)
							(end -0.1778 0.2794)
						)
						(arc
							(start 0.1778 0.2794)
							(mid 0.249642 0.249642)
							(end 0.2794 0.1778)
						)
						(arc
							(start 0.2794 -0.1778)
							(mid 0.249642 -0.249642)
							(end 0.1778 -0.2794)
						)
					)
					(width 0)
					(fill yes)
				)
			)
		)
		(pad "2" smd custom
			(at 0 0.4445 180)
			(size 0.1397 0.1397)
			(layers "F.Cu" "F.Mask" "F.Paste")
			(net "GND")
			(options
				(clearance outline)
				(anchor circle)
			)
			(primitives
				(gr_poly
					(pts
						(arc
							(start -0.1778 -0.2794)
							(mid -0.249642 -0.249642)
							(end -0.2794 -0.1778)
						)
						(arc
							(start -0.2794 0.1778)
							(mid -0.249642 0.249642)
							(end -0.1778 0.2794)
						)
						(arc
							(start 0.1778 0.2794)
							(mid 0.249642 0.249642)
							(end 0.2794 0.1778)
						)
						(arc
							(start 0.2794 -0.1778)
							(mid 0.249642 -0.249642)
							(end 0.1778 -0.2794)
						)
					)
					(width 0)
					(fill yes)
				)
			)
		)
	)
	(footprint ""
		(layer "F.Cu")
		(at 10.922 -94.801182 180)
		(property "Reference" "R426"
			(at 0 0 180)
			(layer "F.SilkS")
			(hide yes)
			(effects
				(font
					(size 1.27 1.27)
				)
			)
		)
		(property "Value" "200KR2F-L-GP"
			(at 0.064008 -3.993896 180)
			(unlocked yes)
			(layer "F.Fab")
			(hide yes)
			(effects
				(font
					(size 1.016 1.016)
					(thickness 0.1524)
				)
			)
		)
		(property "Device Type" "R402H16"
			(at 0.064008 -5.517896 180)
			(unlocked yes)
			(layer "F.Fab")
			(hide yes)
			(effects
				(font
					(size 1.016 1.016)
					(thickness 0.1524)
				)
			)
		)
		(duplicate_pad_numbers_are_jumpers no)
		(fp_line
			(start 0.508 -0.9398)
			(end -0.508 -0.9398)
			(stroke
				(width 0.1524)
				(type default)
			)
			(layer "F.SilkS")
		)
		(fp_line
			(start -0.508 -0.9398)
			(end -0.508 0.9398)
			(stroke
				(width 0.1524)
				(type default)
			)
			(layer "F.SilkS")
		)
		(fp_rect
			(start -0.508 0.9398)
			(end 0.508 -0.9398)
			(stroke
				(width 0)
				(type default)
			)
			(fill no)
			(layer "F.CrtYd")
		)
		(fp_rect
			(start -0.508 0.9398)
			(end 0.508 -0.9398)
			(stroke
				(width 0)
				(type default)
			)
			(fill no)
			(layer "F.Fab")
		)
		(pad "1" smd custom
			(at 0 -0.4445 180)
			(size 0.1397 0.1397)
			(layers "F.Cu" "F.Mask" "F.Paste")
			(net "LS_EN_U40")
			(options
				(clearance outline)
				(anchor circle)
			)
			(primitives
				(gr_poly
					(pts
						(arc
							(start -0.1778 -0.2794)
							(mid -0.249642 -0.249642)
							(end -0.2794 -0.1778)
						)
						(arc
							(start -0.2794 0.1778)
							(mid -0.249642 0.249642)
							(end -0.1778 0.2794)
						)
						(arc
							(start 0.1778 0.2794)
							(mid 0.249642 0.249642)
							(end 0.2794 0.1778)
						)
						(arc
							(start 0.2794 -0.1778)
							(mid 0.249642 -0.249642)
							(end 0.1778 -0.2794)
						)
					)
					(width 0)
					(fill yes)
				)
			)
		)
		(pad "2" smd custom
			(at 0 0.4445 180)
			(size 0.1397 0.1397)
			(layers "F.Cu" "F.Mask" "F.Paste")
			(net "P0V9_PG")
			(options
				(clearance outline)
				(anchor circle)
			)
			(primitives
				(gr_poly
					(pts
						(arc
							(start -0.1778 -0.2794)
							(mid -0.249642 -0.249642)
							(end -0.2794 -0.1778)
						)
						(arc
							(start -0.2794 0.1778)
							(mid -0.249642 0.249642)
							(end -0.1778 0.2794)
						)
						(arc
							(start 0.1778 0.2794)
							(mid 0.249642 0.249642)
							(end 0.2794 0.1778)
						)
						(arc
							(start 0.2794 -0.1778)
							(mid 0.249642 -0.249642)
							(end 0.1778 -0.2794)
						)
					)
					(width 0)
					(fill yes)
				)
			)
		)
	)
	(footprint ""
		(layer "F.Cu")
		(at 168.008808 -55.179214)
		(property "Reference" "TP123"
			(at 0 0 0)
			(layer "F.SilkS")
			(hide yes)
			(effects
				(font
					(size 1.27 1.27)
				)
			)
		)
		(property "Value" "TPAD28-2-GP"
			(at -0.0127 -1.6637 0)
			(unlocked yes)
			(layer "F.Fab")
			(hide yes)
			(effects
				(font
					(size 1.016 1.016)
					(thickness 0.1524)
				)
			)
		)
		(property "Device Type" "TPAD28"
			(at -0.0127 -3.1877 0)
			(unlocked yes)
			(layer "F.Fab")
			(hide yes)
			(effects
				(font
					(size 1.016 1.016)
					(thickness 0.1524)
				)
			)
		)
		(duplicate_pad_numbers_are_jumpers no)
		(fp_poly
			(pts
				(arc
					(start 0.3556 0)
					(mid -0.3556 0)
					(end 0.3556 0)
				)
			)
			(stroke
				(width 0)
				(type default)
			)
			(fill no)
			(layer "F.CrtYd")
		)
		(fp_poly
			(pts
				(arc
					(start 0.6096 0)
					(mid -0.6096 0)
					(end 0.6096 0)
				)
			)
			(stroke
				(width 0)
				(type default)
			)
			(fill no)
			(layer "F.Fab")
		)
		(pad "1" smd circle
			(at 0 0)
			(size 0.7112 0.7112)
			(layers "F.Cu" "F.Mask" "F.Paste")
			(net "ICE0_TRST#")
		)
	)
	(footprint ""
		(layer "F.Cu")
		(at 60.15228 -108.797852 180)
		(property "Reference" "L34"
			(at 0 0 180)
			(layer "F.SilkS")
			(hide yes)
			(effects
				(font
					(size 1.27 1.27)
				)
			)
		)
		(property "Value" "COIL-3D3UH-26-GP"
			(at -4.699 -4.0132 180)
			(unlocked yes)
			(layer "F.Fab")
			(hide yes)
			(effects
				(font
					(size 1.016 1.016)
					(thickness 0.1524)
				)
			)
		)
		(property "Device Type" "L7066-1830-UH119"
			(at -4.699 -5.5372 180)
			(unlocked yes)
			(layer "F.Fab")
			(hide yes)
			(effects
				(font
					(size 1.016 1.016)
					(thickness 0.1524)
				)
			)
		)
		(duplicate_pad_numbers_are_jumpers no)
		(fp_line
			(start 3.556 4.4958)
			(end -3.556 4.4958)
			(stroke
				(width 0.1524)
				(type default)
			)
			(layer "F.SilkS")
		)
		(fp_line
			(start 3.556 -4.4958)
			(end 3.556 4.4958)
			(stroke
				(width 0.1524)
				(type default)
			)
			(layer "F.SilkS")
		)
		(fp_line
			(start -3.556 4.4958)
			(end -3.556 -4.4958)
			(stroke
				(width 0.1524)
				(type default)
			)
			(layer "F.SilkS")
		)
		(fp_line
			(start -3.556 -4.4958)
			(end 3.556 -4.4958)
			(stroke
				(width 0.1524)
				(type default)
			)
			(layer "F.SilkS")
		)
		(fp_rect
			(start -3.302 3.4798)
			(end 3.302 -3.4798)
			(stroke
				(width 0)
				(type default)
			)
			(fill no)
			(layer "F.CrtYd")
		)
		(fp_poly
			(pts
				(xy -3.81 4.572) (xy -3.81 -4.572) (xy 3.81 -4.572) (xy 3.81 -0.5588) (xy 3.302 -0.5588) (xy 3.302 -3.4798)
				(xy -3.302 -3.4798) (xy -3.302 3.4798) (xy 3.302 3.4798) (xy 3.302 -0.5461) (xy 3.81 -0.5461) (xy 3.81 4.572)
			)
			(stroke
				(width 0)
				(type default)
			)
			(fill no)
			(layer "F.CrtYd")
		)
		(fp_rect
			(start -3.81 4.572)
			(end 3.81 -4.572)
			(stroke
				(width 0)
				(type default)
			)
			(fill no)
			(layer "F.Fab")
		)
		(pad "1" smd rect
			(at 0 -2.779522 180)
			(size 3.5052 2.921)
			(layers "F.Cu" "F.Mask" "F.Paste")
			(net "P3V3_LL")
		)
		(pad "2" smd rect
			(at 0 2.779522 180)
			(size 3.5052 2.921)
			(layers "F.Cu" "F.Mask" "F.Paste")
			(net "P3V3_OUT")
		)
	)
)
